(kicad_pcb
	(version 20241229)
	(generator "pcbnew")
	(generator_version "9.0")
	(general
		(thickness 1.6642)
		(legacy_teardrops no)
	)
	(paper "A3")
	(title_block
		(title "PolarFire SoM")
		(date "2025-07-22")
		(rev "1.1.4")
		(company "Antmicro Ltd")
		(comment 1 "www.antmicro.com")
		(comment 9 "footprints 91-93 of 470")
	)
	(layers
		(0 "F.Cu" mixed)
		(4 "In1.Cu" power)
		(6 "In2.Cu" signal)
		(8 "In3.Cu" power)
		(10 "In4.Cu" signal)
		(12 "In5.Cu" power)
		(14 "In6.Cu" power)
		(16 "In7.Cu" signal)
		(18 "In8.Cu" power)
		(20 "In9.Cu" signal)
		(22 "In10.Cu" power)
		(24 "In11.Cu" signal)
		(26 "In12.Cu" signal)
		(2 "B.Cu" mixed)
		(9 "F.Adhes" user "F.Adhesive")
		(11 "B.Adhes" user "B.Adhesive")
		(13 "F.Paste" user)
		(15 "B.Paste" user)
		(5 "F.SilkS" user "F.Silkscreen")
		(7 "B.SilkS" user "B.Silkscreen")
		(1 "F.Mask" user)
		(3 "B.Mask" user)
		(17 "Dwgs.User" user "User.Drawings")
		(19 "Cmts.User" user "User.Comments")
		(21 "Eco1.User" user "User.Eco1")
		(23 "Eco2.User" user "User.Eco2")
		(25 "Edge.Cuts" user)
		(27 "Margin" user)
		(31 "F.CrtYd" user "F.Courtyard")
		(29 "B.CrtYd" user "B.Courtyard")
		(35 "F.Fab" user)
		(33 "B.Fab" user)
	)
	(footprint "antmicro-footprints:TQFN-30-1EP_2.5x4.5mm_P0.4mm_Layout5x10"
		(layer "F.Cu")
		(at 194.39 147.15 -90)
		(descr "2.5mm x 4.5mm ")
		(property "Reference" "U15"
			(at -0.11 -3.54 90)
			(layer "F.SilkS")
			(effects
				(font
					(size 0.7 0.7)
					(thickness 0.15)
				)
				(justify right bottom)
			)
		)
		(property "Value" "PI3HDX511DZLE"
			(at 0 3.7 90)
			(layer "F.Fab")
			(hide yes)
			(effects
				(font
					(size 0.7 0.7)
					(thickness 0.15)
				)
				(justify right bottom)
			)
		)
		(property "Datasheet" "https://eu.mouser.com/datasheet/2/115/diodes_inc_diod-s-a0004145302-1-1749206.pdf"
			(at 0 0 90)
			(layer "F.Fab")
			(hide yes)
			(effects
				(font
					(size 1.27 1.27)
					(thickness 0.15)
				)
			)
		)
		(property "Description" "Video ICs Active HDMI TQFN-30"
			(at 0 0 90)
			(layer "F.Fab")
			(hide yes)
			(effects
				(font
					(size 1.27 1.27)
					(thickness 0.15)
				)
			)
		)
		(property "Author" "Antmicro"
			(at 47.24 341.54 0)
			(layer "F.Fab")
			(hide yes)
			(effects
				(font
					(size 1 1)
					(thickness 0.15)
				)
			)
		)
		(property "License" "Apache-2.0"
			(at 47.24 341.54 0)
			(layer "F.Fab")
			(hide yes)
			(effects
				(font
					(size 1 1)
					(thickness 0.15)
				)
			)
		)
		(property "MPN" "PI3HDX511DZLE"
			(at 47.24 341.54 0)
			(layer "F.Fab")
			(hide yes)
			(effects
				(font
					(size 1 1)
					(thickness 0.15)
				)
			)
		)
		(property "Manufacturer" "Diodes Incorporated"
			(at 47.24 341.54 0)
			(layer "F.Fab")
			(hide yes)
			(effects
				(font
					(size 1 1)
					(thickness 0.15)
				)
			)
		)
		(sheetname "/HDMI/")
		(sheetfile "hdmi.kicad_sch")
		(attr smd)
		(fp_line
			(start 1.033 2.27)
			(end 1.267 2.27)
			(stroke
				(width 0.1)
				(type default)
			)
			(layer "F.SilkS")
		)
		(fp_line
			(start 1.267 2.27)
			(end 1.267 2.016)
			(stroke
				(width 0.1)
				(type default)
			)
			(layer "F.SilkS")
		)
		(fp_line
			(start -1.27 2.269)
			(end -1.016 2.269)
			(stroke
				(width 0.1)
				(type default)
			)
			(layer "F.SilkS")
		)
		(fp_line
			(start -1.27 2.051)
			(end -1.27 2.269)
			(stroke
				(width 0.1)
				(type default)
			)
			(layer "F.SilkS")
		)
		(fp_line
			(start 1.033 -2.27)
			(end 1.267 -2.27)
			(stroke
				(width 0.1)
				(type default)
			)
			(layer "F.SilkS")
		)
		(fp_line
			(start 1.267 -2.27)
			(end 1.267 -2.016)
			(stroke
				(width 0.1)
				(type default)
			)
			(layer "F.SilkS")
		)
		(fp_line
			(start -1.27 -2.274)
			(end -1.27 -2.02)
			(stroke
				(width 0.1)
				(type default)
			)
			(layer "F.SilkS")
		)
		(fp_line
			(start -1.036 -2.274)
			(end -1.27 -2.274)
			(stroke
				(width 0.1)
				(type default)
			)
			(layer "F.SilkS")
		)
		(fp_circle
			(center -1.45 -2.1)
			(end -1.4 -2.1)
			(stroke
				(width 0.15)
				(type solid)
			)
			(fill yes)
			(layer "F.SilkS")
		)
		(fp_rect
			(start -1.6 -2.6)
			(end 1.6 2.6)
			(stroke
				(width 0.05)
				(type solid)
			)
			(fill no)
			(layer "F.CrtYd")
		)
		(fp_text user "${REFERENCE}"
			(at -2.2 7.518 270)
			(layer "F.Fab")
			(effects
				(font
					(size 0.7 0.7)
					(thickness 0.15)
				)
				(justify left bottom)
			)
		)
		(fp_text user "License: Apache-2.0"
			(at -2.2 6.318 270)
			(layer "F.Fab")
			(effects
				(font
					(size 0.7 0.7)
					(thickness 0.15)
				)
				(justify left bottom)
			)
		)
		(fp_text user "Author: Antmicro"
			(at -2.2 8.718 270)
			(layer "F.Fab")
			(effects
				(font
					(size 0.7 0.7)
					(thickness 0.15)
				)
				(justify left bottom)
			)
		)
		(pad "1" smd roundrect
			(at -1.25 -1.8 270)
			(size 0.6 0.2)
			(layers "F.Cu" "F.Mask" "F.Paste")
			(roundrect_rratio 0.06)
			(chamfer_ratio 0.5)
			(chamfer top_right)
			(net 554 "Net-(U15-CEXT)")
			(pinfunction "CEXT")
			(pintype "power_in")
		)
		(pad "2" smd roundrect
			(at -1.25 -1.4 270)
			(size 0.6 0.2)
			(layers "F.Cu" "F.Mask" "F.Paste")
			(roundrect_rratio 0.4)
			(chamfer_ratio 0)
			(chamfer top_left bottom_left)
			(net 549 "/HDMI/PI3HDX_C_TX2_N")
			(pinfunction "IN_D2_N")
			(pintype "input")
		)
		(pad "3" smd roundrect
			(at -1.25 -1 270)
			(size 0.6 0.2)
			(layers "F.Cu" "F.Mask" "F.Paste")
			(roundrect_rratio 0.4)
			(chamfer_ratio 0)
			(chamfer top_left bottom_left)
			(net 57 "/HDMI/PI3HDX_C_TX2_P")
			(pinfunction "IN_D2_P")
			(pintype "input")
		)
		(pad "4" smd roundrect
			(at -1.25 -0.6 270)
			(size 0.6 0.2)
			(layers "F.Cu" "F.Mask" "F.Paste")
			(roundrect_rratio 0.4)
			(chamfer_ratio 0)
			(chamfer top_left bottom_left)
			(net 550 "/HDMI/PI3HDX_C_TX1_N")
			(pinfunction "IN_D1_N")
			(pintype "input")
		)
		(pad "5" smd roundrect
			(at -1.25 -0.2 270)
			(size 0.6 0.2)
			(layers "F.Cu" "F.Mask" "F.Paste")
			(roundrect_rratio 0.4)
			(chamfer_ratio 0)
			(chamfer top_left bottom_left)
			(net 546 "/HDMI/PI3HDX_C_TX1_P")
			(pinfunction "IN_D1_P")
			(pintype "input")
		)
		(pad "6" smd roundrect
			(at -1.25 0.2 270)
			(size 0.6 0.2)
			(layers "F.Cu" "F.Mask" "F.Paste")
			(roundrect_rratio 0.4)
			(chamfer_ratio 0)
			(chamfer top_left bottom_left)
			(net 551 "/HDMI/PI3HDX_C_TX0_N")
			(pinfunction "IN_D0_N")
			(pintype "input")
		)
		(pad "7" smd roundrect
			(at -1.25 0.6 270)
			(size 0.6 0.2)
			(layers "F.Cu" "F.Mask" "F.Paste")
			(roundrect_rratio 0.4)
			(chamfer_ratio 0)
			(chamfer top_left bottom_left)
			(net 547 "/HDMI/PI3HDX_C_TX0_P")
			(pinfunction "IN_D0_P")
			(pintype "input")
		)
		(pad "8" smd roundrect
			(at -1.25 1 270)
			(size 0.6 0.2)
			(layers "F.Cu" "F.Mask" "F.Paste")
			(roundrect_rratio 0.4)
			(chamfer_ratio 0)
			(chamfer top_left bottom_left)
			(net 552 "/HDMI/PI3HDX_C_CLK_N")
			(pinfunction "IN_CLK_N")
			(pintype "input")
		)
		(pad "9" smd roundrect
			(at -1.25 1.4 270)
			(size 0.6 0.2)
			(layers "F.Cu" "F.Mask" "F.Paste")
			(roundrect_rratio 0.4)
			(chamfer_ratio 0)
			(chamfer top_left bottom_left)
			(net 548 "/HDMI/PI3HDX_C_CLK_P")
			(pinfunction "IN_CLK_P")
			(pintype "input")
		)
		(pad "10" smd roundrect
			(at -1.25 1.8 270)
			(size 0.6 0.2)
			(layers "F.Cu" "F.Mask" "F.Paste")
			(roundrect_rratio 0.06)
			(chamfer_ratio 0.5)
			(chamfer bottom_right)
			(net 505 "PI3HDX511F_HOTPLUG")
			(pinfunction "HPD_SRC")
			(pintype "output")
		)
		(pad "11" smd roundrect
			(at -0.8 2.25)
			(size 0.6 0.2)
			(layers "F.Cu" "F.Mask" "F.Paste")
			(roundrect_rratio 0.06)
			(chamfer_ratio 0.5)
			(chamfer top_right)
			(net 622 "/FPGA GPIO/PI3HDX511F.SDA")
			(pinfunction "SDA_SRC")
			(pintype "bidirectional")
		)
		(pad "12" smd roundrect
			(at -0.4 2.25)
			(size 0.6 0.2)
			(layers "F.Cu" "F.Mask" "F.Paste")
			(roundrect_rratio 0.4)
			(chamfer_ratio 0)
			(chamfer top_left bottom_left)
			(net 283 "/FPGA GPIO/PI3HDX511F.SCL")
			(pinfunction "SCL_SRC")
			(pintype "bidirectional")
		)
		(pad "13" smd roundrect
			(at 0 2.25)
			(size 0.6 0.2)
			(layers "F.Cu" "F.Mask" "F.Paste")
			(roundrect_rratio 0.4)
			(chamfer_ratio 0)
			(chamfer top_left bottom_left)
			(net 417 "GND")
			(pinfunction "GND")
			(pintype "passive")
		)
		(pad "14" smd roundrect
			(at 0.4 2.25)
			(size 0.6 0.2)
			(layers "F.Cu" "F.Mask" "F.Paste")
			(roundrect_rratio 0.4)
			(chamfer_ratio 0)
			(chamfer top_left bottom_left)
			(net 555 "Net-(U15-OC_S0)")
			(pinfunction "OC_S0")
			(pintype "input")
		)
		(pad "15" smd roundrect
			(at 0.8 2.25)
			(size 0.6 0.2)
			(layers "F.Cu" "F.Mask" "F.Paste")
			(roundrect_rratio 0.4)
			(chamfer_ratio 0)
			(chamfer top_left bottom_left)
			(net 557 "Net-(U15-EQ_S0)")
			(pinfunction "EQ_S0")
			(pintype "input")
		)
		(pad "16" smd roundrect
			(at 1.25 1.8 270)
			(size 0.6 0.2)
			(layers "F.Cu" "F.Mask" "F.Paste")
			(roundrect_rratio 0.06)
			(chamfer_ratio 0.5)
			(chamfer bottom_left)
			(net 163 "/Bottom Connector/HDMI0.CLK_P")
			(pinfunction "OUT_CLK_P")
			(pintype "output")
		)
		(pad "17" smd roundrect
			(at 1.25 1.4 270)
			(size 0.6 0.2)
			(layers "F.Cu" "F.Mask" "F.Paste")
			(roundrect_rratio 0.4)
			(chamfer_ratio 0)
			(chamfer top_right bottom_right)
			(net 196 "/Bottom Connector/HDMI0.CLK_N")
			(pinfunction "OUT_CLK_N")
			(pintype "output")
		)
		(pad "18" smd roundrect
			(at 1.25 1 270)
			(size 0.6 0.2)
			(layers "F.Cu" "F.Mask" "F.Paste")
			(roundrect_rratio 0.4)
			(chamfer_ratio 0)
			(chamfer top_right bottom_right)
			(net 159 "/Bottom Connector/HDMI0.TX0_P")
			(pinfunction "OUT_D0_P")
			(pintype "output")
		)
		(pad "19" smd roundrect
			(at 1.25 0.6 270)
			(size 0.6 0.2)
			(layers "F.Cu" "F.Mask" "F.Paste")
			(roundrect_rratio 0.4)
			(chamfer_ratio 0)
			(chamfer top_right bottom_right)
			(net 161 "/Bottom Connector/HDMI0.TX0_N")
			(pinfunction "OUT_D0_N")
			(pintype "output")
		)
		(pad "20" smd roundrect
			(at 1.25 0.2 270)
			(size 0.6 0.2)
			(layers "F.Cu" "F.Mask" "F.Paste")
			(roundrect_rratio 0.4)
			(chamfer_ratio 0)
			(chamfer top_right bottom_right)
			(net 553 "/HDMI/HDMI_3V3")
			(pinfunction "VDD")
			(pintype "power_in")
		)
		(pad "21" smd roundrect
			(at 1.25 -0.2 270)
			(size 0.6 0.2)
			(layers "F.Cu" "F.Mask" "F.Paste")
			(roundrect_rratio 0.4)
			(chamfer_ratio 0)
			(chamfer top_right bottom_right)
			(net 147 "/Bottom Connector/HDMI0.TX1_P")
			(pinfunction "OUT_D1_P")
			(pintype "output")
		)
		(pad "22" smd roundrect
			(at 1.25 -0.6 270)
			(size 0.6 0.2)
			(layers "F.Cu" "F.Mask" "F.Paste")
			(roundrect_rratio 0.4)
			(chamfer_ratio 0)
			(chamfer top_right bottom_right)
			(net 157 "/Bottom Connector/HDMI0.TX1_N")
			(pinfunction "OUT_D1_N")
			(pintype "output")
		)
		(pad "23" smd roundrect
			(at 1.25 -1 270)
			(size 0.6 0.2)
			(layers "F.Cu" "F.Mask" "F.Paste")
			(roundrect_rratio 0.4)
			(chamfer_ratio 0)
			(chamfer top_right bottom_right)
			(net 143 "/Bottom Connector/HDMI0.TX2_P")
			(pinfunction "OUT_D2_P")
			(pintype "output")
		)
		(pad "24" smd roundrect
			(at 1.25 -1.4 270)
			(size 0.6 0.2)
			(layers "F.Cu" "F.Mask" "F.Paste")
			(roundrect_rratio 0.4)
			(chamfer_ratio 0)
			(chamfer top_right bottom_right)
			(net 144 "/Bottom Connector/HDMI0.TX2_N")
			(pinfunction "OUT_D2_N")
			(pintype "output")
		)
		(pad "25" smd roundrect
			(at 1.25 -1.8 270)
			(size 0.6 0.2)
			(layers "F.Cu" "F.Mask" "F.Paste")
			(roundrect_rratio 0.06)
			(chamfer_ratio 0.5)
			(chamfer top_left)
			(net 218 "/Bottom Connector/HDMI0.SCL")
			(pinfunction "SCL_SINK")
			(pintype "bidirectional")
		)
		(pad "26" smd roundrect
			(at 0.8 -2.25)
			(size 0.6 0.2)
			(layers "F.Cu" "F.Mask" "F.Paste")
			(roundrect_rratio 0.06)
			(chamfer_ratio 0.5)
			(chamfer bottom_left)
			(net 206 "/Bottom Connector/HDMI0.SDA")
			(pinfunction "SDA_SINK")
			(pintype "bidirectional")
		)
		(pad "27" smd roundrect
			(at 0.4 -2.25)
			(size 0.6 0.2)
			(layers "F.Cu" "F.Mask" "F.Paste")
			(roundrect_rratio 0.4)
			(chamfer_ratio 0)
			(chamfer top_right bottom_right)
			(net 97 "HDMI0_HOTPLUG")
			(pinfunction "HPD_SINK")
			(pintype "input")
		)
		(pad "28" smd roundrect
			(at 0 -2.25)
			(size 0.6 0.2)
			(layers "F.Cu" "F.Mask" "F.Paste")
			(roundrect_rratio 0.4)
			(chamfer_ratio 0)
			(chamfer top_right bottom_right)
			(net 417 "GND")
			(pinfunction "GND")
			(pintype "power_in")
		)
		(pad "29" smd roundrect
			(at -0.4 -2.25)
			(size 0.6 0.2)
			(layers "F.Cu" "F.Mask" "F.Paste")
			(roundrect_rratio 0.4)
			(chamfer_ratio 0)
			(chamfer top_right bottom_right)
			(net 556 "Net-(U15-OEB)")
			(pinfunction "OEB")
			(pintype "input")
		)
		(pad "30" smd roundrect
			(at -0.8 -2.25)
			(size 0.6 0.2)
			(layers "F.Cu" "F.Mask" "F.Paste")
			(roundrect_rratio 0.06)
			(chamfer_ratio 0.5)
			(chamfer top_left)
			(net 553 "/HDMI/HDMI_3V3")
			(pinfunction "VDD")
			(pintype "passive")
		)
		(pad "31" smd roundrect
			(at 0 0)
			(size 3.2 1.2)
			(layers "F.Cu" "F.Mask" "F.Paste")
			(roundrect_rratio 0)
			(chamfer_ratio 0.3)
			(chamfer top_right)
			(net 417 "GND")
			(pinfunction "EP")
			(pintype "power_in")
		)
	)
	(footprint "antmicro-footprints:TP_SMD_0.75mm"
		(layer "F.Cu")
		(at 222.364999 149.23)
		(property "Reference" "TP13"
			(at 12.505001 6.11 90)
			(layer "F.SilkS")
			(hide yes)
			(effects
				(font
					(size 0.7 0.7)
					(thickness 0.15)
				)
				(justify left bottom)
			)
		)
		(property "Value" "TP_0.75mm_SMD"
			(at 0 1.2 0)
			(layer "F.Fab")
			(hide yes)
			(effects
				(font
					(size 0.7 0.7)
					(thickness 0.15)
				)
				(justify left bottom)
			)
		)
		(property "Description" "SMT test point"
			(at 0 0 0)
			(layer "F.Fab")
			(hide yes)
			(effects
				(font
					(size 1.27 1.27)
					(thickness 0.15)
				)
			)
		)
		(property "Author" "Antmicro"
			(at 0 0 0)
			(layer "F.Fab")
			(hide yes)
			(effects
				(font
					(size 1 1)
					(thickness 0.15)
				)
			)
		)
		(property "License" "Apache-2.0"
			(at 0 0 0)
			(layer "F.Fab")
			(hide yes)
			(effects
				(font
					(size 1 1)
					(thickness 0.15)
				)
			)
		)
		(property "MPN" ""
			(at 0 0 0)
			(layer "F.Fab")
			(hide yes)
			(effects
				(font
					(size 1 1)
					(thickness 0.15)
				)
			)
		)
		(property "Manufacturer" ""
			(at 0 0 0)
			(layer "F.Fab")
			(hide yes)
			(effects
				(font
					(size 1 1)
					(thickness 0.15)
				)
			)
		)
		(property "Public" "False"
			(at 0 0 0)
			(layer "F.Fab")
			(hide yes)
			(effects
				(font
					(size 1 1)
					(thickness 0.15)
				)
			)
		)
		(sheetname "/WiFi_Bluetooth/")
		(sheetfile "wifi_bt.kicad_sch")
		(attr exclude_from_pos_files exclude_from_bom)
		(fp_circle
			(center 0 0)
			(end 0.475 0)
			(stroke
				(width 0.05)
				(type default)
			)
			(fill no)
			(layer "F.CrtYd")
		)
		(fp_text user "Author: Antmicro"
			(at -0.4 3.901 0)
			(layer "F.Fab")
			(effects
				(font
					(size 0.7 0.7)
					(thickness 0.15)
				)
				(justify left bottom)
			)
		)
		(fp_text user "License: Apache-2.0"
			(at -0.4 5.101 0)
			(layer "F.Fab")
			(effects
				(font
					(size 0.7 0.7)
					(thickness 0.15)
				)
				(justify left bottom)
			)
		)
		(fp_text user "${REFERENCE}"
			(at -0.4 2.7 0)
			(layer "F.Fab")
			(effects
				(font
					(size 0.7 0.7)
					(thickness 0.15)
				)
				(justify left bottom)
			)
		)
		(pad "1" smd circle
			(at 0 0)
			(size 0.75 0.75)
			(layers "F.Cu" "F.Mask")
			(net 507 "Net-(U26A-BT_PCM_IN)")
			(pinfunction "1")
			(pintype "passive")
		)
	)
	(footprint "antmicro-footprints:R_0402_1005Metric"
		(layer "F.Cu")
		(at 203.35 120.75 90)
		(descr "Resistor SMD 0402")
		(tags "resistor SMD 0402")
		(property "Reference" "R17"
			(at -1.85 4 90)
			(layer "F.SilkS")
			(effects
				(font
					(size 0.7 0.7)
					(thickness 0.15)
				)
				(justify left bottom)
			)
		)
		(property "Value" "R_0R_0402"
			(at -1.011843 1.772047 90)
			(layer "F.Fab")
			(hide yes)
			(effects
				(font
					(size 0.7 0.7)
					(thickness 0.15)
				)
				(justify left bottom)
			)
		)
		(property "Datasheet" "https://industrial.panasonic.com/cdbs/www-data/pdf/RDA0000/AOA0000C301.pdf"
			(at 0 0 90)
			(layer "F.Fab")
			(hide yes)
			(effects
				(font
					(size 1.27 1.27)
					(thickness 0.15)
				)
			)
		)
		(property "Description" "SMD Chip Resistor, Jumper, 0 ohm, 100 mW, 0402 [1005 Metric], Thick Film, General Purpose"
			(at 0 0 90)
			(layer "F.Fab")
			(hide yes)
			(effects
				(font
					(size 1.27 1.27)
					(thickness 0.15)
				)
			)
		)
		(property "Author" "Antmicro"
			(at 324.1 -82.6 0)
			(layer "F.Fab")
			(hide yes)
			(effects
				(font
					(size 1 1)
					(thickness 0.15)
				)
			)
		)
		(property "Current" "1A"
			(at 324.1 -82.6 0)
			(layer "F.Fab")
			(hide yes)
			(effects
				(font
					(size 1 1)
					(thickness 0.15)
				)
			)
		)
		(property "License" "Apache-2.0"
			(at 324.1 -82.6 0)
			(layer "F.Fab")
			(hide yes)
			(effects
				(font
					(size 1 1)
					(thickness 0.15)
				)
			)
		)
		(property "MPN" "ERJ2GE0R00X"
			(at 324.1 -82.6 0)
			(layer "F.Fab")
			(hide yes)
			(effects
				(font
					(size 1 1)
					(thickness 0.15)
				)
			)
		)
		(property "Manufacturer" "Panasonic"
			(at 324.1 -82.6 0)
			(layer "F.Fab")
			(hide yes)
			(effects
				(font
					(size 1 1)
					(thickness 0.15)
				)
			)
		)
		(property "Public" ""
			(at 324.1 -82.6 0)
			(layer "F.Fab")
			(hide yes)
			(effects
				(font
					(size 1 1)
					(thickness 0.15)
				)
			)
		)
		(property "Tolerance" "~"
			(at 324.1 -82.6 0)
			(layer "F.Fab")
			(hide yes)
			(effects
				(font
					(size 1 1)
					(thickness 0.15)
				)
			)
		)
		(property "Val" "0R"
			(at 324.1 -82.6 0)
			(layer "F.Fab")
			(hide yes)
			(effects
				(font
					(size 1 1)
					(thickness 0.15)
				)
			)
		)
		(sheetname "/FPGA MSSIO/")
		(sheetfile "fpga-mssio.kicad_sch")
		(attr smd)
		(fp_rect
			(start -0.925 -0.47)
			(end 0.925 0.47)
			(stroke
				(width 0.05)
				(type default)
			)
			(fill no)
			(layer "F.CrtYd")
		)
		(fp_rect
			(start -0.5 -0.25)
			(end 0.5 0.25)
			(stroke
				(width 0.15)
				(type solid)
			)
			(fill no)
			(layer "F.Fab")
		)
		(fp_text user "Author: Antmicro"
			(at -0.95 4.169 90)
			(layer "F.Fab")
			(effects
				(font
					(size 0.7 0.7)
					(thickness 0.15)
				)
				(justify left bottom)
			)
		)
		(fp_text user "License: Apache-2.0"
			(at -0.95 5.169 90)
			(layer "F.Fab")
			(effects
				(font
					(size 0.7 0.7)
					(thickness 0.15)
				)
				(justify left bottom)
			)
		)
		(fp_text user "${REFERENCE}"
			(at -0.95 3.168 90)
			(layer "F.Fab")
			(effects
				(font
					(size 0.7 0.7)
					(thickness 0.15)
				)
				(justify left bottom)
			)
		)
		(pad "1" smd roundrect
			(at -0.48 0 90)
			(size 0.59 0.64)
			(layers "F.Cu" "F.Mask" "F.Paste")
			(roundrect_rratio 0.25)
			(net 92 "/FPGA MSSIO/SUPPLY.SCL")
			(pintype "passive")
		)
		(pad "2" smd roundrect
			(at 0.48 0 90)
			(size 0.59 0.64)
			(layers "F.Cu" "F.Mask" "F.Paste")
			(roundrect_rratio 0.25)
			(net 94 "/FPGA MSSIO/ID.SCL")
			(pintype "passive")
		)
	)
)
